# T6G (Grand Teton) — schematic netlist excerpt (pin names and nets, part order shuffled) for the footprints in the layout excerpt that follows; sources: Cadence DE-HDL packaged netlist, KiCad conversion of 04192023_DAF0TMB3IC0_F0TG_MB_C_brd_V02_OCP.brd

R6060  Q_RES  4.7K 5% EMPTY  pkg 0402LF  page 140 : A = P12V_OCP_EN_2_R ; B = GND
R4167  Q_RES  100K 1% CHIP  pkg 0402LF  page 124 : A = P3V3_AUX ; B = GPU_3V3IO_RSVD1_ISO

(kicad_pcb
	(version 20260206)
	(generator "pcbnew")
	(generator_version "10.0")
	(general
		(thickness 1.6)
		(legacy_teardrops no)
	)
	(paper "A4")
	(title_block
		(title "04192023_DAF0TMB3IC0_F0TG_MB_C_brd_V02_OCP.brd")
		(comment 1 "Grand Teton / footprints 1169-1170 of 8354")
	)
	(layers
		(0 "F.Cu" signal "TOP")
		(4 "In1.Cu" signal "GND")
		(6 "In2.Cu" signal "IN1")
		(8 "In3.Cu" signal "GND1")
		(10 "In4.Cu" signal "IN2")
		(12 "In5.Cu" signal "GND2")
		(14 "In6.Cu" signal "IN3")
		(16 "In7.Cu" signal "GND3")
		(18 "In8.Cu" signal "VCC")
		(20 "In9.Cu" signal "VCC1")
		(22 "In10.Cu" signal "GND4")
		(24 "In11.Cu" signal "IN4")
		(26 "In12.Cu" signal "GND5")
		(28 "In13.Cu" signal "IN5")
		(30 "In14.Cu" signal "GND6")
		(32 "In15.Cu" signal "IN6")
		(34 "In16.Cu" signal "GND7")
		(2 "B.Cu" signal "BOTTOM")
		(9 "F.Adhes" user "F.Adhesive")
		(11 "B.Adhes" user "B.Adhesive")
		(13 "F.Paste" user "Package Geometry/Pastemask Top")
		(15 "B.Paste" user "Package Geometry/Pastemask Bottom")
		(5 "F.SilkS" user "Ref Des/Silkscreen Top")
		(7 "B.SilkS" user "Ref Des/Silkscreen Bottom")
		(1 "F.Mask" user "Board Geometry/Soldermask Top")
		(3 "B.Mask" user "Board Geometry/Soldermask Bottom")
		(17 "Dwgs.User" user "User.Drawings")
		(19 "Cmts.User" user "User.Comments")
		(21 "Eco1.User" user "User.Eco1")
		(23 "Eco2.User" user "User.Eco2")
		(25 "Edge.Cuts" user "Board Geometry/Outline")
		(27 "Margin" user)
		(31 "F.CrtYd" user "Package Geometry/Place Bound Top")
		(29 "B.CrtYd" user "Package Geometry/Place Bound Bottom")
		(35 "F.Fab" user "Ref Des/Assembly Top")
		(33 "B.Fab" user "Ref Des/Assembly Bottom")
	)
	(footprint ""
		(layer "F.Cu")
		(at 419.230302 -434.386736 90)
		(property "Reference" "R4167"
			(at 0 0 90)
			(layer "F.SilkS")
			(hide yes)
			(effects
				(font
					(size 1.27 1.27)
				)
			)
		)
		(property "Value" ""
			(at 0 0 90)
			(layer "F.Fab")
			(effects
				(font
					(size 1.27 1.27)
				)
			)
		)
		(duplicate_pad_numbers_are_jumpers no)
		(fp_line
			(start 0.7874 -0.4064)
			(end 0.7874 0.4064)
			(stroke
				(width 0.1524)
				(type default)
			)
			(layer "F.SilkS")
		)
		(fp_line
			(start -0.7874 -0.4064)
			(end 0.7874 -0.4064)
			(stroke
				(width 0.1524)
				(type default)
			)
			(layer "F.SilkS")
		)
		(fp_line
			(start 0.7874 0.4064)
			(end -0.7874 0.4064)
			(stroke
				(width 0.1524)
				(type default)
			)
			(layer "F.SilkS")
		)
		(fp_line
			(start -0.7874 0.4064)
			(end -0.7874 -0.4064)
			(stroke
				(width 0.1524)
				(type default)
			)
			(layer "F.SilkS")
		)
		(fp_line
			(start -0.12065 -0.305054)
			(end -0.12065 -0.2794)
			(stroke
				(width 0.1)
				(type default)
			)
			(layer "F.Fab")
		)
		(fp_line
			(start -0.67945 -0.305054)
			(end -0.12065 -0.305054)
			(stroke
				(width 0.1)
				(type default)
			)
			(layer "F.Fab")
		)
		(fp_line
			(start 0.67945 -0.3048)
			(end 0.67945 0.3048)
			(stroke
				(width 0.1)
				(type default)
			)
			(layer "F.Fab")
		)
		(fp_line
			(start 0.12065 -0.3048)
			(end 0.67945 -0.3048)
			(stroke
				(width 0.1)
				(type default)
			)
			(layer "F.Fab")
		)
		(fp_line
			(start 0.12065 -0.2794)
			(end 0.12065 -0.3048)
			(stroke
				(width 0.1)
				(type default)
			)
			(layer "F.Fab")
		)
		(fp_line
			(start -0.12065 -0.2794)
			(end 0.12065 -0.2794)
			(stroke
				(width 0.1)
				(type default)
			)
			(layer "F.Fab")
		)
		(fp_line
			(start 0.120396 0.2794)
			(end -0.12065 0.2794)
			(stroke
				(width 0.1)
				(type default)
			)
			(layer "F.Fab")
		)
		(fp_line
			(start -0.12065 0.2794)
			(end -0.12065 0.3048)
			(stroke
				(width 0.1)
				(type default)
			)
			(layer "F.Fab")
		)
		(fp_line
			(start 0.67945 0.3048)
			(end 0.120396 0.3048)
			(stroke
				(width 0.1)
				(type default)
			)
			(layer "F.Fab")
		)
		(fp_line
			(start 0.120396 0.3048)
			(end 0.120396 0.2794)
			(stroke
				(width 0.1)
				(type default)
			)
			(layer "F.Fab")
		)
		(fp_line
			(start -0.12065 0.3048)
			(end -0.67945 0.3048)
			(stroke
				(width 0.1)
				(type default)
			)
			(layer "F.Fab")
		)
		(fp_line
			(start -0.67945 0.3048)
			(end -0.67945 -0.305054)
			(stroke
				(width 0.1)
				(type default)
			)
			(layer "F.Fab")
		)
		(pad "1" smd circle
			(at -0.40005 0 90)
			(size 0 0)
			(layers "F.Cu" "F.Mask" "F.Paste")
			(net "P3V3_AUX")
		)
		(pad "2" smd circle
			(at 0.40005 0 90)
			(size 0 0)
			(layers "F.Cu" "F.Mask" "F.Paste")
			(net "GPU_3V3IO_RSVD1_ISO")
		)
	)
	(footprint ""
		(layer "F.Cu")
		(at 66.372994 -36.800028)
		(property "Reference" "R6060"
			(at 0 0 0)
			(layer "F.SilkS")
			(hide yes)
			(effects
				(font
					(size 1.27 1.27)
				)
			)
		)
		(property "Value" ""
			(at 0 0 0)
			(layer "F.Fab")
			(effects
				(font
					(size 1.27 1.27)
				)
			)
		)
		(duplicate_pad_numbers_are_jumpers no)
		(fp_line
			(start -0.7874 -0.4064)
			(end 0.7874 -0.4064)
			(stroke
				(width 0.1524)
				(type default)
			)
			(layer "F.SilkS")
		)
		(fp_line
			(start -0.7874 0.4064)
			(end -0.7874 -0.4064)
			(stroke
				(width 0.1524)
				(type default)
			)
			(layer "F.SilkS")
		)
		(fp_line
			(start 0.7874 -0.4064)
			(end 0.7874 0.4064)
			(stroke
				(width 0.1524)
				(type default)
			)
			(layer "F.SilkS")
		)
		(fp_line
			(start 0.7874 0.4064)
			(end -0.7874 0.4064)
			(stroke
				(width 0.1524)
				(type default)
			)
			(layer "F.SilkS")
		)
		(fp_line
			(start -0.67945 -0.305054)
			(end -0.12065 -0.305054)
			(stroke
				(width 0.1)
				(type default)
			)
			(layer "F.Fab")
		)
		(fp_line
			(start -0.67945 0.3048)
			(end -0.67945 -0.305054)
			(stroke
				(width 0.1)
				(type default)
			)
			(layer "F.Fab")
		)
		(fp_line
			(start -0.12065 -0.305054)
			(end -0.12065 -0.2794)
			(stroke
				(width 0.1)
				(type default)
			)
			(layer "F.Fab")
		)
		(fp_line
			(start -0.12065 -0.2794)
			(end 0.12065 -0.2794)
			(stroke
				(width 0.1)
				(type default)
			)
			(layer "F.Fab")
		)
		(fp_line
			(start -0.12065 0.2794)
			(end -0.12065 0.3048)
			(stroke
				(width 0.1)
				(type default)
			)
			(layer "F.Fab")
		)
		(fp_line
			(start -0.12065 0.3048)
			(end -0.67945 0.3048)
			(stroke
				(width 0.1)
				(type default)
			)
			(layer "F.Fab")
		)
		(fp_line
			(start 0.120396 0.2794)
			(end -0.12065 0.2794)
			(stroke
				(width 0.1)
				(type default)
			)
			(layer "F.Fab")
		)
		(fp_line
			(start 0.120396 0.3048)
			(end 0.120396 0.2794)
			(stroke
				(width 0.1)
				(type default)
			)
			(layer "F.Fab")
		)
		(fp_line
			(start 0.12065 -0.3048)
			(end 0.67945 -0.3048)
			(stroke
				(width 0.1)
				(type default)
			)
			(layer "F.Fab")
		)
		(fp_line
			(start 0.12065 -0.2794)
			(end 0.12065 -0.3048)
			(stroke
				(width 0.1)
				(type default)
			)
			(layer "F.Fab")
		)
		(fp_line
			(start 0.67945 -0.3048)
			(end 0.67945 0.3048)
			(stroke
				(width 0.1)
				(type default)
			)
			(layer "F.Fab")
		)
		(fp_line
			(start 0.67945 0.3048)
			(end 0.120396 0.3048)
			(stroke
				(width 0.1)
				(type default)
			)
			(layer "F.Fab")
		)
		(pad "1" smd circle
			(at -0.40005 0)
			(size 0 0)
			(layers "F.Cu" "F.Mask" "F.Paste")
			(net "P12V_OCP_EN_2_R")
		)
		(pad "2" smd circle
			(at 0.40005 0)
			(size 0 0)
			(layers "F.Cu" "F.Mask" "F.Paste")
			(net "GND")
		)
	)
)
